(kicad_pcb
	(version 20241229)
	(generator "pcbnew")
	(generator_version "9.0")
	(general
		(thickness 1.61)
		(legacy_teardrops no)
	)
	(paper "A3")
	(title_block
		(title "SO-DIMM DDR5 Tester")
		(date "2025-11-26")
		(rev "1.3.0")
		(comment 9 "footprints 315-317 of 627")
	)
	(layers
		(0 "F.Cu" signal)
		(4 "In1.Cu" power)
		(6 "In2.Cu" mixed)
		(8 "In3.Cu" power)
		(10 "In4.Cu" mixed)
		(12 "In5.Cu" power)
		(14 "In6.Cu" mixed)
		(16 "In7.Cu" power)
		(18 "In8.Cu" power)
		(20 "In9.Cu" mixed)
		(22 "In10.Cu" power)
		(2 "B.Cu" signal)
		(9 "F.Adhes" user "F.Adhesive")
		(11 "B.Adhes" user "B.Adhesive")
		(13 "F.Paste" user)
		(15 "B.Paste" user)
		(5 "F.SilkS" user "F.Silkscreen")
		(7 "B.SilkS" user "B.Silkscreen")
		(1 "F.Mask" user)
		(3 "B.Mask" user)
		(17 "Dwgs.User" user "User.Drawings")
		(19 "Cmts.User" user "User.Comments")
		(21 "Eco1.User" user "User.Eco1")
		(23 "Eco2.User" user "User.Eco2")
		(25 "Edge.Cuts" user)
		(27 "Margin" user)
		(31 "F.CrtYd" user "F.Courtyard")
		(29 "B.CrtYd" user "B.Courtyard")
		(35 "F.Fab" user)
		(33 "B.Fab" user)
	)
	(footprint "antmicro-footprints:SC70-3"
		(layer "F.Cu")
		(at 156.700501 177.476)
		(property "Reference" "Q15"
			(at 0 -1.6 0)
			(layer "F.SilkS")
			(hide yes)
			(effects
				(font
					(size 0.7 0.7)
					(thickness 0.15)
				)
				(justify left bottom)
			)
		)
		(property "Value" "BSS138PW,115"
			(at 0 2.3 0)
			(layer "F.Fab")
			(effects
				(font
					(size 0.7 0.7)
					(thickness 0.15)
				)
				(justify left bottom)
			)
		)
		(property "Datasheet" "https://assets.nexperia.com/documents/data-sheet/BSS138PW.pdf"
			(at 0 0 0)
			(layer "F.Fab")
			(hide yes)
			(effects
				(font
					(size 1.27 1.27)
					(thickness 0.15)
				)
			)
		)
		(property "Description" "Power MOSFET, N Channel, 60 V, 320 mA, 0.9 ohm, SOT-323, Surface Mount"
			(at 0 0 0)
			(layer "F.Fab")
			(hide yes)
			(effects
				(font
					(size 1.27 1.27)
					(thickness 0.15)
				)
			)
		)
		(property "Author" "Antmicro"
			(at 0 0 0)
			(layer "F.Fab")
			(hide yes)
			(effects
				(font
					(size 1 1)
					(thickness 0.15)
				)
			)
		)
		(property "License" "Apache-2.0"
			(at 0 0 0)
			(layer "F.Fab")
			(hide yes)
			(effects
				(font
					(size 1 1)
					(thickness 0.15)
				)
			)
		)
		(property "MPN" "BSS138PW,115"
			(at 0 0 0)
			(layer "F.Fab")
			(hide yes)
			(effects
				(font
					(size 1 1)
					(thickness 0.15)
				)
			)
		)
		(property "Manufacturer" "Nexperia"
			(at 0 0 0)
			(layer "F.Fab")
			(hide yes)
			(effects
				(font
					(size 1 1)
					(thickness 0.15)
				)
			)
		)
		(sheetname "/Supply/")
		(sheetfile "supply.kicad_sch")
		(attr smd)
		(fp_line
			(start -0.3 -1)
			(end 0.627 -0.999)
			(stroke
				(width 0.15)
				(type solid)
			)
			(layer "F.SilkS")
		)
		(fp_line
			(start -0.3 1)
			(end 0.627 1.001)
			(stroke
				(width 0.15)
				(type solid)
			)
			(layer "F.SilkS")
		)
		(fp_line
			(start 0.627 -0.6)
			(end 0.627 -0.999)
			(stroke
				(width 0.15)
				(type solid)
			)
			(layer "F.SilkS")
		)
		(fp_line
			(start 0.627 0.6)
			(end 0.627 1.001)
			(stroke
				(width 0.15)
				(type solid)
			)
			(layer "F.SilkS")
		)
		(fp_line
			(start -1.4 1)
			(end -1.4 -1)
			(stroke
				(width 0.05)
				(type solid)
			)
			(layer "F.CrtYd")
		)
		(fp_line
			(start -0.9 -1.3)
			(end -0.9 -1)
			(stroke
				(width 0.05)
				(type solid)
			)
			(layer "F.CrtYd")
		)
		(fp_line
			(start -0.9 -1.3)
			(end 0.9 -1.3)
			(stroke
				(width 0.05)
				(type solid)
			)
			(layer "F.CrtYd")
		)
		(fp_line
			(start -0.9 -1)
			(end -1.4 -1)
			(stroke
				(width 0.05)
				(type solid)
			)
			(layer "F.CrtYd")
		)
		(fp_line
			(start -0.9 1)
			(end -1.4 1)
			(stroke
				(width 0.05)
				(type solid)
			)
			(layer "F.CrtYd")
		)
		(fp_line
			(start -0.9 1.3)
			(end -0.9 1)
			(stroke
				(width 0.05)
				(type solid)
			)
			(layer "F.CrtYd")
		)
		(fp_line
			(start 0.9 -1.3)
			(end 0.9 -0.4)
			(stroke
				(width 0.05)
				(type solid)
			)
			(layer "F.CrtYd")
		)
		(fp_line
			(start 0.9 -0.4)
			(end 1.4 -0.4)
			(stroke
				(width 0.05)
				(type solid)
			)
			(layer "F.CrtYd")
		)
		(fp_line
			(start 0.9 0.4)
			(end 0.9 1.3)
			(stroke
				(width 0.05)
				(type solid)
			)
			(layer "F.CrtYd")
		)
		(fp_line
			(start 0.9 1.3)
			(end -0.9 1.3)
			(stroke
				(width 0.05)
				(type solid)
			)
			(layer "F.CrtYd")
		)
		(fp_line
			(start 1.4 -0.4)
			(end 1.4 0.4)
			(stroke
				(width 0.05)
				(type solid)
			)
			(layer "F.CrtYd")
		)
		(fp_line
			(start 1.4 0.4)
			(end 0.9 0.4)
			(stroke
				(width 0.05)
				(type solid)
			)
			(layer "F.CrtYd")
		)
		(fp_rect
			(start -0.623 -0.999)
			(end 0.627 1.001)
			(stroke
				(width 0.15)
				(type solid)
			)
			(fill no)
			(layer "F.Fab")
		)
		(pad "1" smd rect
			(at -1.051 -0.65 90)
			(size 0.6 0.6)
			(layers "F.Cu" "F.Mask" "F.Paste")
			(net 272 "FAN_PWM")
			(pinfunction "G")
			(pintype "input")
		)
		(pad "2" smd rect
			(at -1.051 0.65 90)
			(size 0.6 0.6)
			(layers "F.Cu" "F.Mask" "F.Paste")
			(net 1 "GND")
			(pinfunction "S")
			(pintype "passive")
		)
		(pad "3" smd rect
			(at 1.05 0 90)
			(size 0.6 0.6)
			(layers "F.Cu" "F.Mask" "F.Paste")
			(net 332 "Net-(J8-Pin_4)")
			(pinfunction "D")
			(pintype "passive")
		)
	)
	(footprint "antmicro-footprints:MP_Pad6mm_Drill3mm"
		(layer "F.Cu")
		(at 76.375501 204.951)
		(property "Reference" "MP2"
			(at 0 -3.2 0)
			(layer "F.SilkS")
			(hide yes)
			(effects
				(font
					(size 0.7 0.7)
					(thickness 0.15)
				)
				(justify left bottom)
			)
		)
		(property "Value" "MP_Pad6mm_Drill3mm"
			(at 0 3.9 0)
			(layer "F.Fab")
			(effects
				(font
					(size 0.7 0.7)
					(thickness 0.15)
				)
				(justify left bottom)
			)
		)
		(attr board_only exclude_from_pos_files exclude_from_bom)
		(pad "1" thru_hole circle
			(at 0 0)
			(size 6 6)
			(drill 3)
			(layers "*.Cu" "*.Mask")
			(remove_unused_layers no)
			(net 1 "GND")
		)
	)
	(footprint "antmicro-footprints:Fiducial_1mm_Mask2mm"
		(layer "F.Cu")
		(at 197.010501 197.696 180)
		(descr "Circular Fiducial, 1mm bare copper, 3mm soldermask opening")
		(tags "fiducial")
		(property "Reference" "FID1005"
			(at 0 -1.4 0)
			(layer "F.SilkS")
			(hide yes)
			(effects
				(font
					(size 0.7 0.7)
					(thickness 0.15)
				)
				(justify right bottom)
			)
		)
		(property "Value" "Fiducial_1mm_Mask2mm"
			(at 0 2.2 0)
			(layer "F.Fab")
			(effects
				(font
					(size 0.7 0.7)
					(thickness 0.15)
				)
				(justify right bottom)
			)
		)
		(property "Author" "Antmicro"
			(at 394.021002 395.392 0)
			(layer "F.Fab")
			(hide yes)
			(effects
				(font
					(size 1 1)
					(thickness 0.15)
				)
			)
		)
		(property "License" "Apache-2.0"
			(at 394.021002 395.392 0)
			(layer "F.Fab")
			(hide yes)
			(effects
				(font
					(size 1 1)
					(thickness 0.15)
				)
			)
		)
		(property "MPN" ""
			(at 394.021002 395.392 0)
			(layer "F.Fab")
			(hide yes)
			(effects
				(font
					(size 1 1)
					(thickness 0.15)
				)
			)
		)
		(property "Manufacturer" ""
			(at 394.021002 395.392 0)
			(layer "F.Fab")
			(hide yes)
			(effects
				(font
					(size 1 1)
					(thickness 0.15)
				)
			)
		)
		(sheetfile "sodimm-ddr5-tester.kicad_sch")
		(attr board_only exclude_from_pos_files exclude_from_bom)
		(fp_circle
			(center 0 0)
			(end 1.24 0)
			(stroke
				(width 0.05)
				(type solid)
			)
			(fill no)
			(layer "F.CrtYd")
		)
		(fp_circle
			(center 0 0)
			(end 0.999 0)
			(stroke
				(width 0.15)
				(type solid)
			)
			(fill no)
			(layer "F.Fab")
		)
		(pad "" smd circle
			(at 0 0 180)
			(size 1 1)
			(layers "F.Cu" "F.Mask")
			(solder_mask_margin 0.5)
			(clearance 0.5)
		)
	)
)
